(kicad_pcb
	(version 20260206)
	(generator "pcbnew")
	(generator_version "10.0")
	(general
		(thickness 1.6)
		(legacy_teardrops no)
	)
	(paper "A4")
	(title_block
		(title "04192023_DAF0TMB3IC0_F0TG_MB_C_brd_V02_OCP.brd")
		(comment 1 "Grand Teton / footprints 622-624 of 8354")
	)
	(layers
		(0 "F.Cu" signal "TOP")
		(4 "In1.Cu" signal "GND")
		(6 "In2.Cu" signal "IN1")
		(8 "In3.Cu" signal "GND1")
		(10 "In4.Cu" signal "IN2")
		(12 "In5.Cu" signal "GND2")
		(14 "In6.Cu" signal "IN3")
		(16 "In7.Cu" signal "GND3")
		(18 "In8.Cu" signal "VCC")
		(20 "In9.Cu" signal "VCC1")
		(22 "In10.Cu" signal "GND4")
		(24 "In11.Cu" signal "IN4")
		(26 "In12.Cu" signal "GND5")
		(28 "In13.Cu" signal "IN5")
		(30 "In14.Cu" signal "GND6")
		(32 "In15.Cu" signal "IN6")
		(34 "In16.Cu" signal "GND7")
		(2 "B.Cu" signal "BOTTOM")
		(9 "F.Adhes" user "F.Adhesive")
		(11 "B.Adhes" user "B.Adhesive")
		(13 "F.Paste" user "Package Geometry/Pastemask Top")
		(15 "B.Paste" user "Package Geometry/Pastemask Bottom")
		(5 "F.SilkS" user "Ref Des/Silkscreen Top")
		(7 "B.SilkS" user "Ref Des/Silkscreen Bottom")
		(1 "F.Mask" user "Board Geometry/Soldermask Top")
		(3 "B.Mask" user "Board Geometry/Soldermask Bottom")
		(17 "Dwgs.User" user "User.Drawings")
		(19 "Cmts.User" user "User.Comments")
		(21 "Eco1.User" user "User.Eco1")
		(23 "Eco2.User" user "User.Eco2")
		(25 "Edge.Cuts" user "Board Geometry/Outline")
		(27 "Margin" user)
		(31 "F.CrtYd" user "Package Geometry/Place Bound Top")
		(29 "B.CrtYd" user "Package Geometry/Place Bound Bottom")
		(35 "F.Fab" user "Ref Des/Assembly Top")
		(33 "B.Fab" user "Ref Des/Assembly Bottom")
	)
	(footprint ""
		(layer "F.Cu")
		(at 25.331166 -73.614788 -90)
		(property "Reference" "JP6000"
			(at 2.451354 6.528054 0)
			(unlocked yes)
			(layer "F.SilkS")
			(effects
				(font
					(size 0.7874 0.5842)
					(thickness 0.1524)
				)
				(justify left)
			)
		)
		(property "Value" ""
			(at 0 0 270)
			(layer "F.Fab")
			(effects
				(font
					(size 1.27 1.27)
				)
			)
		)
		(duplicate_pad_numbers_are_jumpers no)
		(fp_line
			(start -1.249934 6.400038)
			(end -1.249934 -1.320038)
			(stroke
				(width 0.1524)
				(type default)
			)
			(layer "F.SilkS")
		)
		(fp_line
			(start 1.249934 6.400038)
			(end -1.249934 6.400038)
			(stroke
				(width 0.1524)
				(type default)
			)
			(layer "F.SilkS")
		)
		(fp_line
			(start -1.249934 -1.320038)
			(end 1.249934 -1.320038)
			(stroke
				(width 0.1524)
				(type default)
			)
			(layer "F.SilkS")
		)
		(fp_line
			(start 1.249934 -1.320038)
			(end 1.249934 6.400038)
			(stroke
				(width 0.1524)
				(type default)
			)
			(layer "F.SilkS")
		)
		(fp_poly
			(pts
				(xy -2.5654 -0.556514) (xy -1.452372 0) (xy -2.5654 0.556514)
			)
			(stroke
				(width 0)
				(type default)
			)
			(fill yes)
			(layer "F.SilkS")
		)
		(fp_line
			(start -1.249934 6.400038)
			(end -1.249934 -1.320038)
			(stroke
				(width 0.1)
				(type default)
			)
			(layer "F.Fab")
		)
		(fp_line
			(start 1.249934 6.400038)
			(end -1.249934 6.400038)
			(stroke
				(width 0.1)
				(type default)
			)
			(layer "F.Fab")
		)
		(fp_line
			(start -1.249934 -1.320038)
			(end 1.249934 -1.320038)
			(stroke
				(width 0.1)
				(type default)
			)
			(layer "F.Fab")
		)
		(fp_line
			(start 1.249934 -1.320038)
			(end 1.249934 6.400038)
			(stroke
				(width 0.1)
				(type default)
			)
			(layer "F.Fab")
		)
		(fp_poly
			(pts
				(xy -2.5654 -0.556514) (xy -1.452372 0) (xy -2.5654 0.556514)
			)
			(stroke
				(width 0)
				(type default)
			)
			(fill yes)
			(layer "F.Fab")
		)
		(fp_text user "3"
			(at -1.778 5.13207 270)
			(unlocked yes)
			(layer "F.SilkS")
			(effects
				(font
					(size 0.7874 0.5842)
					(thickness 0.1524)
				)
			)
		)
		(fp_text user "3"
			(at -1.1557 5.18287 270)
			(unlocked yes)
			(layer "B.SilkS")
			(effects
				(font
					(size 0.7874 0.5842)
					(thickness 0.1524)
				)
				(justify mirror)
			)
		)
		(fp_text user "1"
			(at -1.143 0.02667 270)
			(unlocked yes)
			(layer "B.SilkS")
			(effects
				(font
					(size 0.7874 0.5842)
					(thickness 0.1524)
				)
				(justify mirror)
			)
		)
		(fp_text user "3"
			(at -1.1557 5.18287 270)
			(unlocked yes)
			(layer "B.Fab")
			(effects
				(font
					(size 0.7874 0.5842)
					(thickness 0.1524)
				)
				(justify mirror)
			)
		)
		(fp_text user "1"
			(at -1.143 0.02667 270)
			(unlocked yes)
			(layer "B.Fab")
			(effects
				(font
					(size 0.7874 0.5842)
					(thickness 0.1524)
				)
				(justify mirror)
			)
		)
		(fp_text user "3"
			(at -1.778 5.13207 270)
			(unlocked yes)
			(layer "F.Fab")
			(effects
				(font
					(size 0.7874 0.5842)
					(thickness 0.1524)
				)
			)
		)
		(pad "1" thru_hole rect
			(at 0 0 270)
			(size 1.5494 1.5494)
			(drill 1.0414)
			(layers "*.Cu" "*.Mask")
			(remove_unused_layers no)
			(net "PU_U212_EN_N")
			(clearance 0)
			(padstack
				(mode front_inner_back)
				(layer "Inner"
					(shape circle)
					(size 1.5494 1.5494)
					(clearance 0)
				)
				(layer "B.Cu"
					(shape rect)
					(size 1.5494 1.5494)
					(clearance 0)
				)
			)
		)
		(pad "2" thru_hole circle
			(at 0 2.54 270)
			(size 1.5494 1.5494)
			(drill 1.0414)
			(layers "*.Cu" "*.Mask")
			(remove_unused_layers no)
			(net "U212_EN_N")
			(clearance 0)
		)
		(pad "3" thru_hole circle
			(at 0 5.08 270)
			(size 1.5494 1.5494)
			(drill 1.0414)
			(layers "*.Cu" "*.Mask")
			(remove_unused_layers no)
			(net "PD_U212_EN_N")
			(clearance 0)
		)
	)
	(footprint ""
		(layer "F.Cu")
		(at 316.23 -364.617 90)
		(property "Reference" "PC14"
			(at 0 0 90)
			(layer "F.SilkS")
			(hide yes)
			(effects
				(font
					(size 1.27 1.27)
				)
			)
		)
		(property "Value" ""
			(at 0 0 90)
			(layer "F.Fab")
			(effects
				(font
					(size 1.27 1.27)
				)
			)
		)
		(duplicate_pad_numbers_are_jumpers no)
		(fp_line
			(start 0.7874 -0.4064)
			(end 0.7874 0.4064)
			(stroke
				(width 0.1524)
				(type default)
			)
			(layer "F.SilkS")
		)
		(fp_line
			(start -0.7874 -0.4064)
			(end 0.7874 -0.4064)
			(stroke
				(width 0.1524)
				(type default)
			)
			(layer "F.SilkS")
		)
		(fp_line
			(start 0.7874 0.4064)
			(end -0.7874 0.4064)
			(stroke
				(width 0.1524)
				(type default)
			)
			(layer "F.SilkS")
		)
		(fp_line
			(start -0.7874 0.4064)
			(end -0.7874 -0.4064)
			(stroke
				(width 0.1524)
				(type default)
			)
			(layer "F.SilkS")
		)
		(fp_line
			(start -0.12065 -0.305054)
			(end -0.12065 -0.2794)
			(stroke
				(width 0.1)
				(type default)
			)
			(layer "F.Fab")
		)
		(fp_line
			(start -0.67945 -0.305054)
			(end -0.12065 -0.305054)
			(stroke
				(width 0.1)
				(type default)
			)
			(layer "F.Fab")
		)
		(fp_line
			(start 0.67945 -0.3048)
			(end 0.67945 0.3048)
			(stroke
				(width 0.1)
				(type default)
			)
			(layer "F.Fab")
		)
		(fp_line
			(start 0.12065 -0.3048)
			(end 0.67945 -0.3048)
			(stroke
				(width 0.1)
				(type default)
			)
			(layer "F.Fab")
		)
		(fp_line
			(start 0.12065 -0.2794)
			(end 0.12065 -0.3048)
			(stroke
				(width 0.1)
				(type default)
			)
			(layer "F.Fab")
		)
		(fp_line
			(start -0.12065 -0.2794)
			(end 0.12065 -0.2794)
			(stroke
				(width 0.1)
				(type default)
			)
			(layer "F.Fab")
		)
		(fp_line
			(start 0.120396 0.2794)
			(end -0.12065 0.2794)
			(stroke
				(width 0.1)
				(type default)
			)
			(layer "F.Fab")
		)
		(fp_line
			(start -0.12065 0.2794)
			(end -0.12065 0.3048)
			(stroke
				(width 0.1)
				(type default)
			)
			(layer "F.Fab")
		)
		(fp_line
			(start 0.67945 0.3048)
			(end 0.120396 0.3048)
			(stroke
				(width 0.1)
				(type default)
			)
			(layer "F.Fab")
		)
		(fp_line
			(start 0.120396 0.3048)
			(end 0.120396 0.2794)
			(stroke
				(width 0.1)
				(type default)
			)
			(layer "F.Fab")
		)
		(fp_line
			(start -0.12065 0.3048)
			(end -0.67945 0.3048)
			(stroke
				(width 0.1)
				(type default)
			)
			(layer "F.Fab")
		)
		(fp_line
			(start -0.67945 0.3048)
			(end -0.67945 -0.305054)
			(stroke
				(width 0.1)
				(type default)
			)
			(layer "F.Fab")
		)
		(pad "1" smd circle
			(at -0.40005 0 90)
			(size 0 0)
			(layers "F.Cu" "F.Mask" "F.Paste")
			(net "PVDDCR_CPU1_P0_VCC")
		)
		(pad "2" smd circle
			(at 0.40005 0 90)
			(size 0 0)
			(layers "F.Cu" "F.Mask" "F.Paste")
			(net "GND")
		)
	)
	(footprint ""
		(layer "F.Cu")
		(at 436.052722 -406.33396)
		(property "Reference" "R1406"
			(at 0 0 0)
			(layer "F.SilkS")
			(hide yes)
			(effects
				(font
					(size 1.27 1.27)
				)
			)
		)
		(property "Value" ""
			(at 0 0 0)
			(layer "F.Fab")
			(effects
				(font
					(size 1.27 1.27)
				)
			)
		)
		(duplicate_pad_numbers_are_jumpers no)
		(fp_line
			(start -0.32512 -0.175006)
			(end 0.32512 -0.175006)
			(stroke
				(width 0.1)
				(type default)
			)
			(layer "F.Fab")
		)
		(fp_line
			(start -0.32512 0.175006)
			(end -0.32512 -0.175006)
			(stroke
				(width 0.1)
				(type default)
			)
			(layer "F.Fab")
		)
		(fp_line
			(start 0.32512 -0.175006)
			(end 0.32512 0.175006)
			(stroke
				(width 0.1)
				(type default)
			)
			(layer "F.Fab")
		)
		(fp_line
			(start 0.32512 0.175006)
			(end -0.32512 0.175006)
			(stroke
				(width 0.1)
				(type default)
			)
			(layer "F.Fab")
		)
		(pad "1" smd rect
			(at -0.2667 0)
			(size 0.3048 0.381)
			(layers "F.Cu" "F.Mask" "F.Paste")
			(net "RXDET_BYP_RT_CPU0_P2")
		)
		(pad "2" smd rect
			(at 0.2667 0 180)
			(size 0.3048 0.381)
			(layers "F.Cu" "F.Mask" "F.Paste")
			(net "GND")
		)
	)
)
